FILE_TYPE = CONNECTIVITY;
{Allegro Design Entry HDL 17.4-2019 S026 (4007227) 1/17/2022}
"PAGE_NUMBER" = 91;
0"NC";
1"GND\g";
2"GND\g";
3"P3V3\g";
4"P3V3\g";
5"P3V3_AUX\g";
6"M_G_CPU0_SA_DQ<31:0>";
7"M_G_CPU0_SA_CA<6:0>";
8"M_G_CPU0_SB_CA<6:0>";
9"M_G_CPU0_SB_DQS_DP<9:0>";
10"M_G_CPU0_SB_DQS_DN<9:0>";
11"M_G_CPU0_SA_DQS_DP<9:0>";
12"M_G_CPU0_SA_DQS_DN<9:0>";
13"M_G_CPU0_SB_DQ<31:0>";
14"M_G_CPU0_SB_CB<7:0>";
15"M_G_CPU0_SA_CB<7:0>";
16"I3C_SPD_DDRGL_CPU0_SDA";
17"PD_CHG_CPU0_DIMM0_SAA";
18"P3V3_AUX\g";
19"M_G_CPU0_SB_DQ<21>";
20"M_G_CPU0_SB_DQ<26>";
21"M_G_CPU0_SA_CB<6>";
22"I3C_SPD_DDRGL_CPU0_SCL";
23"I3C_SPD_DDRG_CPU0_SDA";
24"PWRGD_CHG_CPU0_DIMM0";
25"GND\g";
26"GND\g";
27"GND\g";
28"P12V_MEM_CPU0\g";
29"P3V3_AUX\g";
30"P3V3_AUX\g";
31"M_G_CPU0_RESET_N";
32"M_G_CPU0_ALERT_N";
33"I3C_SPD_DDRG_CPU0_SCL";
34"PWRGD_CHGL_CPU0";
35"PWRGD_CHGL_CPU0";
36"PWRGD_CHGL_CPU0_R1";
37"PWRGD_CHGL_CPU0_R2";
38"M_G_CPU0_SB_RSP<0>";
39"PD_CHG_CPU0_DIMM0_SAA";
40"M_G_CPU0_SA_CB<7>";
41"M_G_CPU0_SA_CB<4>";
42"M_G_CPU0_SA_CB<1>";
43"M_G_CPU0_SB_CB<7>";
44"M_G_CPU0_SB_CA<0>";
45"M_G_CPU0_SA_CA<1>";
46"M_G_CPU0_SB_CA<1>";
47"M_G_CPU0_SA_CA<2>";
48"M_G_CPU0_SB_CA<2>";
49"M_G_CPU0_SA_CA<3>";
50"M_G_CPU0_SA_CA<4>";
51"M_G_CPU0_SA_CA<5>";
52"M_G_CPU0_SA_CA<6>";
53"M_G_CPU0_SA_CB<5>";
54"M_G_CPU0_SA_CB<3>";
55"M_G_CPU0_SA_CB<2>";
56"M_G_CPU0_SA_CB<0>";
57"M_G_CPU0_SB_CB<6>";
58"M_G_CPU0_SB_CB<5>";
59"M_G_CPU0_SB_CB<4>";
60"M_G_CPU0_SB_CB<3>";
61"M_G_CPU0_SB_CB<2>";
62"M_G_CPU0_SB_CB<1>";
63"M_G_CPU0_SB_CB<0>";
64"M_G_CPU0_CLK_DN<0>";
65"M_G_CPU0_CLK_DP<0>";
66"M_G_CPU0_SA_CS_N<0>";
67"M_G_CPU0_SB_CS_N<0>";
68"M_G_CPU0_SB_CS_N<1>";
69"M_G_CPU0_SA_DQ<29>";
70"M_G_CPU0_SA_DQ<28>";
71"M_G_CPU0_SA_DQ<27>";
72"M_G_CPU0_SA_DQ<14>";
73"M_G_CPU0_SA_DQ<6>";
74"M_G_CPU0_SA_DQ<5>";
75"M_G_CPU0_SA_DQ<4>";
76"M_G_CPU0_SA_DQ<3>";
77"M_G_CPU0_SA_DQ<2>";
78"M_G_CPU0_SA_DQ<1>";
79"M_G_CPU0_SA_DQ<0>";
80"M_G_CPU0_SB_DQ<31>";
81"M_G_CPU0_SB_DQ<30>";
82"M_G_CPU0_SB_DQ<29>";
83"M_G_CPU0_SB_DQ<28>";
84"M_G_CPU0_SB_DQ<27>";
85"M_G_CPU0_SB_DQ<25>";
86"M_G_CPU0_SB_DQ<24>";
87"M_G_CPU0_SB_DQ<23>";
88"M_G_CPU0_SB_DQ<22>";
89"M_G_CPU0_SB_DQ<20>";
90"M_G_CPU0_SB_DQ<19>";
91"M_G_CPU0_SB_DQ<18>";
92"M_G_CPU0_SB_DQ<17>";
93"M_G_CPU0_SB_DQ<16>";
94"M_G_CPU0_SB_DQ<15>";
95"M_G_CPU0_SB_DQ<14>";
96"M_G_CPU0_SB_DQ<13>";
97"M_G_CPU0_SB_DQ<12>";
98"M_G_CPU0_SB_DQ<11>";
99"M_G_CPU0_SB_DQ<10>";
100"M_G_CPU0_SB_DQ<9>";
101"M_G_CPU0_SB_DQ<8>";
102"M_G_CPU0_SB_DQ<7>";
103"M_G_CPU0_SB_DQ<6>";
104"M_G_CPU0_SB_DQ<5>";
105"M_G_CPU0_SB_DQ<4>";
106"M_G_CPU0_SB_DQ<3>";
107"M_G_CPU0_SB_DQ<2>";
108"M_G_CPU0_SB_DQ<1>";
109"M_G_CPU0_SB_DQ<0>";
110"M_G_CPU0_SA_PAR";
111"M_G_CPU0_SB_PAR";
112"M_G_CPU0_SA_DQ<31>";
113"M_G_CPU0_SA_DQ<30>";
114"M_G_CPU0_SA_DQ<25>";
115"M_G_CPU0_SA_DQ<24>";
116"M_G_CPU0_SA_DQ<23>";
117"M_G_CPU0_SA_DQ<22>";
118"M_G_CPU0_SA_DQS_DN<7>";
119"M_G_CPU0_SA_DQS_DP<6>";
120"M_G_CPU0_SB_DQS_DP<8>";
121"M_G_CPU0_SB_DQS_DN<8>";
122"M_G_CPU0_SB_DQS_DP<7>";
123"M_G_CPU0_SA_DQS_DN<0>";
124"M_G_CPU0_SA_DQS_DP<0>";
125"M_G_CPU0_SB_DQS_DN<0>";
126"M_G_CPU0_SB_DQS_DP<0>";
127"M_G_CPU0_SA_DQS_DN<1>";
128"M_G_CPU0_SA_DQS_DP<1>";
129"M_G_CPU0_SB_DQS_DN<1>";
130"M_G_CPU0_SB_DQS_DP<1>";
131"M_G_CPU0_SA_DQS_DN<2>";
132"M_G_CPU0_SA_DQS_DP<2>";
133"M_G_CPU0_SB_DQS_DN<2>";
134"M_G_CPU0_SB_DQS_DP<2>";
135"M_G_CPU0_SA_DQS_DN<3>";
136"M_G_CPU0_SA_DQS_DP<3>";
137"M_G_CPU0_SB_DQS_DN<3>";
138"M_G_CPU0_SB_DQS_DP<3>";
139"M_G_CPU0_SA_DQS_DN<4>";
140"M_G_CPU0_SA_DQS_DP<4>";
141"M_G_CPU0_SB_DQS_DN<4>";
142"M_G_CPU0_SB_DQS_DP<4>";
143"M_G_CPU0_SA_DQS_DN<5>";
144"M_G_CPU0_SA_DQS_DP<5>";
145"M_G_CPU0_SB_DQS_DN<5>";
146"M_G_CPU0_SB_DQS_DP<5>";
147"M_G_CPU0_SA_DQS_DN<6>";
148"M_G_CPU0_SB_DQS_DN<6>";
149"M_G_CPU0_SB_DQS_DP<6>";
150"M_G_CPU0_SA_DQS_DP<7>";
151"M_G_CPU0_SB_DQS_DN<7>";
152"M_G_CPU0_SA_DQS_DN<8>";
153"M_G_CPU0_SA_DQS_DP<8>";
154"M_G_CPU0_SA_DQS_DN<9>";
155"M_G_CPU0_SA_DQS_DP<9>";
156"M_G_CPU0_SB_DQS_DN<9>";
157"M_G_CPU0_SB_DQS_DP<9>";
158"M_G_CPU0_SA_DQ<19>";
159"M_G_CPU0_SA_DQ<20>";
160"M_G_CPU0_SA_DQ<21>";
161"M_G_CPU0_SA_DQ<7>";
162"M_G_CPU0_SA_DQ<8>";
163"M_G_CPU0_SA_DQ<9>";
164"M_G_CPU0_SA_DQ<10>";
165"M_G_CPU0_SA_DQ<11>";
166"M_G_CPU0_SA_DQ<18>";
167"M_G_CPU0_SA_DQ<17>";
168"M_G_CPU0_SA_DQ<16>";
169"M_G_CPU0_SA_DQ<15>";
170"M_G_CPU0_SA_DQ<13>";
171"M_G_CPU0_SA_DQ<12>";
172"M_G_CPU0_SB_CA<3>";
173"M_G_CPU0_SB_CA<4>";
174"M_G_CPU0_SB_CA<5>";
175"M_G_CPU0_SB_CA<6>";
176"M_G_CPU0_SA_CA<0>";
177"M_G_CPU0_SA_DQ<26>";
178"M_G_CPU0_SA_CS_N<1>";
179"M_G_CPU0_SA_RSP<0>";
180"PWRGD_CHGL_CPU0";
%"TAP"
"1","(-5625,4100)","0","mstr_standard","I100";
;
CDS_LIB"mstr_standard"
BODY_TYPE"PLUMBING"
HDL_TAP"TRUE";
"B \NAC \NWC"6;
"S \NAC"
BN"5"74;
%"TAP"
"1","(-5625,4250)","0","mstr_standard","I101";
;
CDS_LIB"mstr_standard"
BODY_TYPE"PLUMBING"
HDL_TAP"TRUE";
"B \NAC \NWC"6;
"S \NAC"
BN"8"162;
%"TAP"
"1","(-5625,4300)","0","mstr_standard","I102";
;
CDS_LIB"mstr_standard"
BODY_TYPE"PLUMBING"
HDL_TAP"TRUE";
"B \NAC \NWC"6;
"S \NAC"
BN"9"163;
%"TAP"
"1","(-5625,4200)","0","mstr_standard","I103";
;
CDS_LIB"mstr_standard"
BODY_TYPE"PLUMBING"
HDL_TAP"TRUE";
"B \NAC \NWC"6;
"S \NAC"
BN"7"161;
%"TAP"
"1","(-5625,4450)","0","mstr_standard","I104";
;
CDS_LIB"mstr_standard"
BODY_TYPE"PLUMBING"
HDL_TAP"TRUE";
"B \NAC \NWC"6;
"S \NAC"
BN"12"171;
%"TAP"
"1","(-5625,4400)","0","mstr_standard","I105";
;
CDS_LIB"mstr_standard"
BODY_TYPE"PLUMBING"
HDL_TAP"TRUE";
"B \NAC \NWC"6;
"S \NAC"
BN"11"165;
%"TAP"
"1","(-5625,4350)","0","mstr_standard","I106";
;
CDS_LIB"mstr_standard"
BODY_TYPE"PLUMBING"
HDL_TAP"TRUE";
"B \NAC \NWC"6;
"S \NAC"
BN"10"164;
%"TAP"
"1","(-5625,4500)","0","mstr_standard","I107";
;
CDS_LIB"mstr_standard"
BODY_TYPE"PLUMBING"
HDL_TAP"TRUE";
"B \NAC \NWC"6;
"S \NAC"
BN"13"170;
%"TAP"
"1","(-5625,4550)","0","mstr_standard","I108";
;
CDS_LIB"mstr_standard"
BODY_TYPE"PLUMBING"
HDL_TAP"TRUE";
"B \NAC \NWC"6;
"S \NAC"
BN"14"72;
%"TAP"
"1","(-5625,4700)","0","mstr_standard","I109";
;
CDS_LIB"mstr_standard"
BODY_TYPE"PLUMBING"
HDL_TAP"TRUE";
"B \NAC \NWC"6;
"S \NAC"
BN"17"167;
%"TAP"
"1","(-5625,4650)","0","mstr_standard","I110";
;
CDS_LIB"mstr_standard"
BODY_TYPE"PLUMBING"
HDL_TAP"TRUE";
"B \NAC \NWC"6;
"S \NAC"
BN"16"168;
%"TAP"
"1","(-5625,4600)","0","mstr_standard","I111";
;
CDS_LIB"mstr_standard"
BODY_TYPE"PLUMBING"
HDL_TAP"TRUE";
"B \NAC \NWC"6;
"S \NAC"
BN"15"169;
%"TAP"
"1","(-5625,4750)","0","mstr_standard","I112";
;
CDS_LIB"mstr_standard"
BODY_TYPE"PLUMBING"
HDL_TAP"TRUE";
"B \NAC \NWC"6;
"S \NAC"
BN"18"166;
%"TAP"
"1","(-5625,4800)","0","mstr_standard","I113";
;
CDS_LIB"mstr_standard"
BODY_TYPE"PLUMBING"
HDL_TAP"TRUE";
"B \NAC \NWC"6;
"S \NAC"
BN"19"158;
%"TAP"
"1","(-5625,4950)","0","mstr_standard","I114";
;
CDS_LIB"mstr_standard"
BODY_TYPE"PLUMBING"
HDL_TAP"TRUE";
"B \NAC \NWC"6;
"S \NAC"
BN"22"117;
%"TAP"
"1","(-5625,4900)","0","mstr_standard","I115";
;
CDS_LIB"mstr_standard"
BODY_TYPE"PLUMBING"
HDL_TAP"TRUE";
"B \NAC \NWC"6;
"S \NAC"
BN"21"160;
%"TAP"
"1","(-5625,4850)","0","mstr_standard","I116";
;
CDS_LIB"mstr_standard"
BODY_TYPE"PLUMBING"
HDL_TAP"TRUE";
"B \NAC \NWC"6;
"S \NAC"
BN"20"159;
%"TAP"
"1","(-5625,5050)","0","mstr_standard","I117";
;
CDS_LIB"mstr_standard"
BODY_TYPE"PLUMBING"
HDL_TAP"TRUE";
"B \NAC \NWC"6;
"S \NAC"
BN"24"115;
%"TAP"
"1","(-5625,5000)","0","mstr_standard","I118";
;
CDS_LIB"mstr_standard"
BODY_TYPE"PLUMBING"
HDL_TAP"TRUE";
"B \NAC \NWC"6;
"S \NAC"
BN"23"116;
%"TAP"
"1","(-5625,5150)","0","mstr_standard","I119";
;
CDS_LIB"mstr_standard"
BODY_TYPE"PLUMBING"
HDL_TAP"TRUE";
"B \NAC \NWC"6;
"S \NAC"
BN"26"177;
%"TAP"
"1","(-5625,5200)","0","mstr_standard","I120";
;
CDS_LIB"mstr_standard"
BODY_TYPE"PLUMBING"
HDL_TAP"TRUE";
"B \NAC \NWC"6;
"S \NAC"
BN"27"71;
%"TAP"
"1","(-5625,5100)","0","mstr_standard","I121";
;
CDS_LIB"mstr_standard"
BODY_TYPE"PLUMBING"
HDL_TAP"TRUE";
"B \NAC \NWC"6;
"S \NAC"
BN"25"114;
%"TAP"
"1","(-5625,5350)","0","mstr_standard","I122";
;
CDS_LIB"mstr_standard"
BODY_TYPE"PLUMBING"
HDL_TAP"TRUE";
"B \NAC \NWC"6;
"S \NAC"
BN"30"113;
%"TAP"
"1","(-5625,5250)","0","mstr_standard","I123";
;
CDS_LIB"mstr_standard"
BODY_TYPE"PLUMBING"
HDL_TAP"TRUE";
"B \NAC \NWC"6;
"S \NAC"
BN"28"70;
%"TAP"
"1","(-5625,5300)","0","mstr_standard","I124";
;
CDS_LIB"mstr_standard"
BODY_TYPE"PLUMBING"
HDL_TAP"TRUE";
"B \NAC \NWC"6;
"S \NAC"
BN"29"69;
%"TAP"
"1","(-5625,5400)","0","mstr_standard","I125";
;
CDS_LIB"mstr_standard"
BODY_TYPE"PLUMBING"
HDL_TAP"TRUE";
"B \NAC \NWC"6;
"S \NAC"
BN"31"112;
%"GND"
"1","(-6025,975)","0","mstr_symbols","I128";
;
BOM_COST"MEM"
SIZE"1B"
CDS_LIB"mstr_symbols"
VOLTAGE"0.0"
BODY_TYPE"PLUMBING"
HDL_POWER"GND";
"A\NAC"1;
%"Q_RES"
"2","(-6025,1200)","0","pure_quanta","I129";
;
LOCATION"R35"
SEC"1"
TOLERANCE"1%"
PACK_TYPE"0402LF"
VALUE"10K"
MATERIAL"CHIP"
WATTAGE"1/16W"
CDS_LIB"pure_quanta"
BOM_COST"MEM"
SEC_TYPE"0402LF"
ROOM""
PART_NUMBER"CS31002FB08";
"A"
$PN"1"
XNET_PINS"3"39;
"B"
$PN"2"
XNET_PINS"2"1;
%"GND"
"1","(-1975,1900)","0","mstr_symbols","I130";
;
CDS_LIB"mstr_symbols"
SIZE"1B"
VOLTAGE"0.0"
BODY_TYPE"PLUMBING"
HDL_POWER"GND";
"A\NAC"25;
%"GND"
"1","(-375,1700)","0","mstr_symbols","I146";
;
SIZE"1B"
CDS_LIB"mstr_symbols"
VOLTAGE"0.0"
BODY_TYPE"PLUMBING"
HDL_POWER"GND";
"A\NAC"26;
%"SCONN288_DDR506112002KQ"
"3","(-1175,3650)","0","pure_quanta","I177";
;
LOCATION"J16"
$SEC"3"
CDS_SEC"3"
VALUE"SCONN288_DDR506112002KQ"
PART_TYPE"SMLF"
MATERIAL"IO"
CDS_LMAN_SYM_OUTLINE"-450,1800,450,-1750"
NEEDS_NO_SIZE"TRUE"
CDS_LIB"pure_quanta"
PART_NUMBER"DFHST8FS479";
"G3"
$PN"G3"26;
"G2"
$PN"G2"26;
"G1"
$PN"G1"26;
"VSS62"
$PN"141"26;
"VSS61"
$PN"139"26;
"VSS60"
$PN"136"26;
"VSS58"
$PN"132"26;
"VSS104"
$PN"240"25;
"VSS102"
$PN"235"25;
"VSS100"
$PN"230"25;
"VIN_BULK2"
$PN"146"28;
"VIN_BULK1"
$PN"145"28;
"VIN_BULK0"
$PN"1"28;
"VSS126"
$PN"288"25;
"VSS125"
$PN"286"25;
"VSS124"
$PN"284"25;
"VSS123"
$PN"281"25;
"VSS122"
$PN"279"25;
"VSS121"
$PN"277"25;
"VSS120"
$PN"275"25;
"VSS119"
$PN"273"25;
"VSS118"
$PN"270"25;
"VSS117"
$PN"268"25;
"VSS116"
$PN"266"25;
"VSS115"
$PN"264"25;
"VSS114"
$PN"262"25;
"VSS113"
$PN"259"25;
"VSS112"
$PN"257"25;
"VSS111"
$PN"255"25;
"VSS110"
$PN"253"25;
"VSS109"
$PN"251"25;
"VSS108"
$PN"248"25;
"VSS107"
$PN"246"25;
"VSS106"
$PN"244"25;
"VSS105"
$PN"242"25;
"VSS103"
$PN"237"25;
"VSS101"
$PN"233"25;
"VSS99"
$PN"228"25;
"VSS98"
$PN"226"25;
"VSS97"
$PN"224"25;
"VSS96"
$PN"222"25;
"VSS95"
$PN"219"25;
"VSS94"
$PN"216"25;
"VSS93"
$PN"214"25;
"VSS92"
$PN"212"25;
"VSS91"
$PN"210"25;
"VSS90"
$PN"208"25;
"VSS89"
$PN"206"25;
"VSS88"
$PN"204"25;
"VSS87"
$PN"202"25;
"VSS86"
$PN"199"25;
"VSS85"
$PN"197"25;
"VSS84"
$PN"195"25;
"VSS83"
$PN"193"25;
"VSS82"
$PN"191"25;
"VSS81"
$PN"188"25;
"VSS80"
$PN"186"25;
"VSS79"
$PN"184"25;
"VSS78"
$PN"182"25;
"VSS77"
$PN"180"25;
"VSS76"
$PN"177"25;
"VSS75"
$PN"175"25;
"VSS74"
$PN"173"25;
"VSS73"
$PN"171"25;
"VSS72"
$PN"169"25;
"VSS71"
$PN"166"25;
"VSS70"
$PN"164"25;
"VSS69"
$PN"162"25;
"VSS68"
$PN"160"25;
"VSS67"
$PN"158"25;
"VSS66"
$PN"155"25;
"VSS65"
$PN"153"25;
"VSS64"
$PN"151"25;
"VSS63"
$PN"143"26;
"VSS59"
$PN"134"26;
"VSS57"
$PN"130"26;
"VSS56"
$PN"128"26;
"VSS55"
$PN"125"26;
"VSS54"
$PN"123"26;
"VSS53"
$PN"121"26;
"VSS52"
$PN"119"26;
"VSS51"
$PN"117"26;
"VSS50"
$PN"114"26;
"VSS49"
$PN"112"26;
"VSS48"
$PN"110"26;
"VSS47"
$PN"108"26;
"VSS46"
$PN"106"26;
"VSS45"
$PN"103"26;
"VSS44"
$PN"101"26;
"VSS43"
$PN"99"26;
"VSS42"
$PN"97"26;
"VSS41"
$PN"95"26;
"VSS40"
$PN"92"26;
"VSS39"
$PN"90"26;
"VSS38"
$PN"88"26;
"VSS37"
$PN"85"26;
"VSS36"
$PN"83"26;
"VSS35"
$PN"81"26;
"VSS34"
$PN"79"26;
"VSS33"
$PN"77"26;
"VSS32"
$PN"75"26;
"VSS31"
$PN"73"26;
"VSS30"
$PN"71"26;
"VSS29"
$PN"69"26;
"VSS28"
$PN"67"26;
"VSS27"
$PN"65"26;
"VSS26"
$PN"63"26;
"VSS25"
$PN"61"26;
"VSS24"
$PN"59"26;
"VSS23"
$PN"57"26;
"VSS22"
$PN"54"26;
"VSS21"
$PN"52"26;
"VSS20"
$PN"50"26;
"VSS19"
$PN"48"26;
"VSS18"
$PN"46"26;
"VSS17"
$PN"43"26;
"VSS16"
$PN"41"26;
"VSS15"
$PN"39"26;
"VSS14"
$PN"37"26;
"VSS13"
$PN"35"26;
"VSS12"
$PN"32"26;
"VSS11"
$PN"30"26;
"VSS10"
$PN"28"26;
"VSS9"
$PN"26"26;
"VSS8"
$PN"24"26;
"VSS7"
$PN"21"26;
"VSS6"
$PN"19"26;
"VSS5"
$PN"17"26;
"VSS4"
$PN"15"26;
"VSS3"
$PN"13"26;
"VSS2"
$PN"10"26;
"VSS1"
$PN"8"26;
"VSS0"
$PN"6"26;
%"Q_CAP"
"1","(-8500,3225)","2","pure_quanta","I183";
;
LOCATION"C112"
$SEC"1"
CDS_SEC"1"
VOLTAGE"25V"
VALUE"0.1UF"
MATERIAL"X7R"
TOLERANCE"10%"
PACK_TYPE"0402"
BOM_COST"MEM"
CDS_LIB"pure_quanta"
ROOM""
PART_NUMBER"CH4104K1B00";
"B"
$PN"2"2;
"A"
$PN"1"18;
%"GND"
"1","(-8500,3000)","0","mstr_symbols","I184";
;
CDS_LIB"mstr_symbols"
SIZE"1B"
BOM_COST"MEM"
VOLTAGE"0"
ROOM"MEM_EFGH_DECOUPLING_CAPS"
BODY_TYPE"PLUMBING"
HDL_POWER"GND";
"A\NAC"2;
%"Q_RES"
"1","(-8350,2150)","2","pure_quanta","I186";
;
LOCATION"R297"
$SEC"1"
CDS_SEC"1"
VALUE"1K"
TOLERANCE"1%"
CDS_LIB"pure_quanta"
BOM_COST"MEM"
WATTAGE"1/16W"
MATERIAL"CHIP"
PACK_TYPE"0402LF"
ROOM""
PART_NUMBER"CS21002FB06";
"B"
$PN"2"34;
"A"
$PN"1"24;
%"Q_RES"
"2","(-8225,2300)","0","pure_quanta","I187";
;
LOCATION"R96"
$SEC"1"
CDS_SEC"1"
TOLERANCE"1%"
WATTAGE"1/16W"
MATERIAL"EMPTY"
VALUE"1K"
PACK_TYPE"0402LF"
CDS_LIB"pure_quanta"
BOM_COST"MEM"
ROOM""
PART_NUMBER"CS21002FB06";
"A"
$PN"1"3;
"B"
$PN"2"24;
%"VCC_CORE"
"1","(-8225,2475)","0","mstr_symbols","I188";
;
HDL_POWER"P3V3"
CDS_LIB"mstr_symbols"
VOLTAGE"3.3"
ROOM"PVCCINFAON_CPU0_CTRL";
"A"3;
%"VCC_CORE"
"1","(-8475,2475)","0","mstr_symbols","I189";
;
HDL_POWER"P3V3"
CDS_LIB"mstr_symbols"
VOLTAGE"3.3"
ROOM"PVCCINFAON_CPU0_CTRL";
"A"4;
%"Q_RES"
"2","(-8475,2300)","2","pure_quanta","I190";
;
LOCATION"R95"
$SEC"1"
CDS_SEC"1"
PACK_TYPE"0402LF"
VALUE"1K"
TOLERANCE"1%"
WATTAGE"1/16W"
MATERIAL"EMPTY"
BOM_COST"MEM"
CDS_LIB"pure_quanta"
ROOM""
PART_NUMBER"CS21002FB06";
"A"
$PN"1"4;
"B"
$PN"2"34;
%"TAP"
"1","(-2900,4525)","0","mstr_standard","I196";
;
CDS_LIB"mstr_standard"
BODY_TYPE"PLUMBING"
HDL_TAP"TRUE";
"B \NAC \NWC"12;
"S \NAC"
BN"9"154;
%"TAP"
"1","(-2900,4425)","0","mstr_standard","I197";
;
CDS_LIB"mstr_standard"
BODY_TYPE"PLUMBING"
HDL_TAP"TRUE";
"B \NAC \NWC"12;
"S \NAC"
BN"8"152;
%"TAP"
"1","(-3100,4575)","0","mstr_standard","I198";
;
CDS_LIB"mstr_standard"
BODY_TYPE"PLUMBING"
HDL_TAP"TRUE";
"B \NAC \NWC"11;
"S \NAC"
BN"9"155;
%"TAP"
"1","(-3100,4475)","0","mstr_standard","I199";
;
CDS_LIB"mstr_standard"
BODY_TYPE"PLUMBING"
HDL_TAP"TRUE";
"B \NAC \NWC"11;
"S \NAC"
BN"8"153;
%"TAP"
"1","(-3100,4375)","0","mstr_standard","I200";
;
CDS_LIB"mstr_standard"
BODY_TYPE"PLUMBING"
HDL_TAP"TRUE";
"B \NAC \NWC"11;
"S \NAC"
BN"7"150;
%"TAP"
"1","(-2900,4325)","0","mstr_standard","I201";
;
CDS_LIB"mstr_standard"
BODY_TYPE"PLUMBING"
HDL_TAP"TRUE";
"B \NAC \NWC"12;
"S \NAC"
BN"7"118;
%"TAP"
"1","(-2900,4125)","0","mstr_standard","I202";
;
CDS_LIB"mstr_standard"
BODY_TYPE"PLUMBING"
HDL_TAP"TRUE";
"B \NAC \NWC"12;
"S \NAC"
BN"5"143;
%"TAP"
"1","(-2900,4225)","0","mstr_standard","I203";
;
CDS_LIB"mstr_standard"
BODY_TYPE"PLUMBING"
HDL_TAP"TRUE";
"B \NAC \NWC"12;
"S \NAC"
BN"6"147;
%"TAP"
"1","(-2900,4025)","0","mstr_standard","I204";
;
CDS_LIB"mstr_standard"
BODY_TYPE"PLUMBING"
HDL_TAP"TRUE";
"B \NAC \NWC"12;
"S \NAC"
BN"4"139;
%"TAP"
"1","(-2900,3925)","0","mstr_standard","I205";
;
CDS_LIB"mstr_standard"
BODY_TYPE"PLUMBING"
HDL_TAP"TRUE";
"B \NAC \NWC"12;
"S \NAC"
BN"3"135;
%"TAP"
"1","(-3100,4175)","0","mstr_standard","I206";
;
CDS_LIB"mstr_standard"
BODY_TYPE"PLUMBING"
HDL_TAP"TRUE";
"B \NAC \NWC"11;
"S \NAC"
BN"5"144;
%"TAP"
"1","(-3100,4275)","0","mstr_standard","I207";
;
CDS_LIB"mstr_standard"
BODY_TYPE"PLUMBING"
HDL_TAP"TRUE";
"B \NAC \NWC"11;
"S \NAC"
BN"6"119;
%"TAP"
"1","(-3100,4075)","0","mstr_standard","I208";
;
CDS_LIB"mstr_standard"
BODY_TYPE"PLUMBING"
HDL_TAP"TRUE";
"B \NAC \NWC"11;
"S \NAC"
BN"4"140;
%"TAP"
"1","(-3100,3875)","0","mstr_standard","I209";
;
CDS_LIB"mstr_standard"
BODY_TYPE"PLUMBING"
HDL_TAP"TRUE";
"B \NAC \NWC"11;
"S \NAC"
BN"2"132;
%"TAP"
"1","(-3100,3975)","0","mstr_standard","I210";
;
CDS_LIB"mstr_standard"
BODY_TYPE"PLUMBING"
HDL_TAP"TRUE";
"B \NAC \NWC"11;
"S \NAC"
BN"3"136;
%"TAP"
"1","(-2900,3825)","0","mstr_standard","I211";
;
CDS_LIB"mstr_standard"
BODY_TYPE"PLUMBING"
HDL_TAP"TRUE";
"B \NAC \NWC"12;
"S \NAC"
BN"2"131;
%"TAP"
"1","(-2900,3725)","0","mstr_standard","I212";
;
CDS_LIB"mstr_standard"
BODY_TYPE"PLUMBING"
HDL_TAP"TRUE";
"B \NAC \NWC"12;
"S \NAC"
BN"1"127;
%"TAP"
"1","(-2900,3625)","0","mstr_standard","I213";
;
CDS_LIB"mstr_standard"
BODY_TYPE"PLUMBING"
HDL_TAP"TRUE";
"B \NAC \NWC"12;
"S \NAC"
BN"0"123;
%"TAP"
"1","(-2900,3475)","0","mstr_standard","I214";
;
CDS_LIB"mstr_standard"
BODY_TYPE"PLUMBING"
HDL_TAP"TRUE";
"B \NAC \NWC"10;
"S \NAC"
BN"9"156;
%"TAP"
"1","(-2900,3375)","0","mstr_standard","I215";
;
CDS_LIB"mstr_standard"
BODY_TYPE"PLUMBING"
HDL_TAP"TRUE";
"B \NAC \NWC"10;
"S \NAC"
BN"8"121;
%"TAP"
"1","(-3100,3675)","0","mstr_standard","I216";
;
CDS_LIB"mstr_standard"
BODY_TYPE"PLUMBING"
HDL_TAP"TRUE";
"B \NAC \NWC"11;
"S \NAC"
BN"0"124;
%"TAP"
"1","(-3100,3775)","0","mstr_standard","I217";
;
CDS_LIB"mstr_standard"
BODY_TYPE"PLUMBING"
HDL_TAP"TRUE";
"B \NAC \NWC"11;
"S \NAC"
BN"1"128;
%"TAP"
"1","(-3100,3425)","0","mstr_standard","I218";
;
CDS_LIB"mstr_standard"
BODY_TYPE"PLUMBING"
HDL_TAP"TRUE";
"B \NAC \NWC"9;
"S \NAC"
BN"8"120;
%"TAP"
"1","(-3100,3525)","0","mstr_standard","I219";
;
CDS_LIB"mstr_standard"
BODY_TYPE"PLUMBING"
HDL_TAP"TRUE";
"B \NAC \NWC"9;
"S \NAC"
BN"9"157;
%"SCONN288_DDR506112002KQ"
"1","(-6475,3650)","0","pure_quanta","I22";
;
LOCATION"J16"
$SEC"1"
CDS_SEC"1"
MATERIAL"IO"
PART_TYPE"SMLF"
VALUE"SCONN288_DDR506112002KQ"
CDS_LMAN_SYM_OUTLINE"-450,1900,450,-1850"
NEEDS_NO_SIZE"TRUE"
CDS_LIB"pure_quanta"
PART_NUMBER"DFHST8FS479";
"PWR_GOOD||FAIL_N"
$PN"147"24;
"DQ31_A"
$PN"194"112;
"CB7_A"
$PN"205"40;
"CB4_A"
$PN"58"41;
"CB1_A"
$PN"53"42;
"CB7_B"
$PN"236"43;
"ALERT_N \B"
$PN"62"32;
"CA0_A"
$PN"66"176;
"CA0_B"
$PN"76"44;
"CA1_A"
$PN"211"45;
"CA1_B"
$PN"221"46;
"CA2_A"
$PN"68"47;
"CA2_B"
$PN"78"48;
"CA3_A"
$PN"213"49;
"CA3_B"
$PN"223"172;
"CA4_A"
$PN"70"50;
"CA4_B"
$PN"80"173;
"CA5_A"
$PN"215"51;
"CA5_B"
$PN"225"174;
"CA6_A"
$PN"72"52;
"CA6_B"
$PN"82"175;
"CB6_A"
$PN"203"21;
"CB5_A"
$PN"60"53;
"CB3_A"
$PN"198"54;
"CB2_A"
$PN"196"55;
"CB0_A"
$PN"51"56;
"CB6_B"
$PN"234"57;
"CB5_B"
$PN"91"58;
"CB4_B"
$PN"89"59;
"CB3_B"
$PN"243"60;
"CB2_B"
$PN"241"61;
"CB1_B"
$PN"98"62;
"CB0_B"
$PN"96"63;
"CK_C \B"
$PN"218"64;
"CK_T"
$PN"217"65;
"CS0_A_N"
$PN"64"66;
"CS0_B_N"
$PN"84"67;
"CS1_A_N"
$PN"209"178;
"CS1_B_N"
$PN"229"68;
"DQ30_A"
$PN"192"113;
"DQ29_A"
$PN"49"69;
"DQ28_A"
$PN"47"70;
"DQ27_A"
$PN"187"71;
"DQ26_A"
$PN"185"177;
"DQ25_A"
$PN"42"114;
"DQ24_A"
$PN"40"115;
"DQ23_A"
$PN"183"116;
"DQ22_A"
$PN"181"117;
"DQ21_A"
$PN"38"160;
"DQ20_A"
$PN"36"159;
"DQ19_A"
$PN"176"158;
"DQ18_A"
$PN"174"166;
"DQ17_A"
$PN"31"167;
"DQ16_A"
$PN"29"168;
"DQ15_A"
$PN"172"169;
"DQ14_A"
$PN"170"72;
"DQ13_A"
$PN"27"170;
"DQ12_A"
$PN"25"171;
"DQ11_A"
$PN"165"165;
"DQ10_A"
$PN"163"164;
"DQ9_A"
$PN"20"163;
"DQ8_A"
$PN"18"162;
"DQ7_A"
$PN"161"161;
"DQ6_A"
$PN"159"73;
"DQ5_A"
$PN"16"74;
"DQ4_A"
$PN"14"75;
"DQ3_A"
$PN"154"76;
"DQ2_A"
$PN"152"77;
"DQ1_A"
$PN"9"78;
"DQ0_A"
$PN"7"79;
"DQ31_B"
$PN"287"80;
"DQ30_B"
$PN"285"81;
"DQ29_B"
$PN"142"82;
"DQ28_B"
$PN"140"83;
"DQ27_B"
$PN"280"84;
"DQ26_B"
$PN"278"20;
"DQ25_B"
$PN"135"85;
"DQ24_B"
$PN"133"86;
"DQ23_B"
$PN"276"87;
"DQ22_B"
$PN"274"88;
"DQ21_B"
$PN"131"19;
"DQ20_B"
$PN"129"89;
"DQ19_B"
$PN"269"90;
"DQ18_B"
$PN"267"91;
"DQ17_B"
$PN"124"92;
"DQ16_B"
$PN"122"93;
"DQ15_B"
$PN"265"94;
"DQ14_B"
$PN"263"95;
"DQ13_B"
$PN"120"96;
"DQ12_B"
$PN"118"97;
"DQ11_B"
$PN"258"98;
"DQ10_B"
$PN"256"99;
"DQ9_B"
$PN"113"100;
"DQ8_B"
$PN"111"101;
"DQ7_B"
$PN"254"102;
"DQ6_B"
$PN"252"103;
"DQ5_B"
$PN"109"104;
"DQ4_B"
$PN"107"105;
"DQ3_B"
$PN"247"106;
"DQ2_B"
$PN"245"107;
"DQ1_B"
$PN"102"108;
"DQ0_B"
$PN"100"109;
"HAS"
$PN"148"17;
"HSCL"
$PN"4"33;
"HSDA"
$PN"5"23;
"LBD||RSP_A_N"
$PN"86"179;
"LBS||RSP_B_N"
$PN"87"38;
"PAR_A"
$PN"74"110;
"PAR_B"
$PN"227"111;
"RESET_N \B"
$PN"207"31;
"RFU6"
$PN"232"0;
"RFU5"
$PN"231"0;
"RFU4"
$PN"220"0;
"RFU3"
$PN"150"0;
"RFU2"
$PN"149"0;
"RFU1"
$PN"144"0;
"RFU0"
$PN"2"0;
"VIN_MGMT"
$PN"3"18;
%"TAP"
"1","(-2900,3275)","0","mstr_standard","I220";
;
CDS_LIB"mstr_standard"
BODY_TYPE"PLUMBING"
HDL_TAP"TRUE";
"B \NAC \NWC"10;
"S \NAC"
BN"7"151;
%"TAP"
"1","(-2900,3175)","0","mstr_standard","I221";
;
CDS_LIB"mstr_standard"
BODY_TYPE"PLUMBING"
HDL_TAP"TRUE";
"B \NAC \NWC"10;
"S \NAC"
BN"6"148;
%"TAP"
"1","(-2900,3075)","0","mstr_standard","I222";
;
CDS_LIB"mstr_standard"
BODY_TYPE"PLUMBING"
HDL_TAP"TRUE";
"B \NAC \NWC"10;
"S \NAC"
BN"5"145;
%"TAP"
"1","(-2900,2975)","0","mstr_standard","I223";
;
CDS_LIB"mstr_standard"
BODY_TYPE"PLUMBING"
HDL_TAP"TRUE";
"B \NAC \NWC"10;
"S \NAC"
BN"4"141;
%"TAP"
"1","(-2900,2875)","0","mstr_standard","I224";
;
CDS_LIB"mstr_standard"
BODY_TYPE"PLUMBING"
HDL_TAP"TRUE";
"B \NAC \NWC"10;
"S \NAC"
BN"3"137;
%"TAP"
"1","(-3100,3225)","0","mstr_standard","I225";
;
CDS_LIB"mstr_standard"
BODY_TYPE"PLUMBING"
HDL_TAP"TRUE";
"B \NAC \NWC"9;
"S \NAC"
BN"6"149;
%"TAP"
"1","(-3100,3325)","0","mstr_standard","I226";
;
CDS_LIB"mstr_standard"
BODY_TYPE"PLUMBING"
HDL_TAP"TRUE";
"B \NAC \NWC"9;
"S \NAC"
BN"7"122;
%"TAP"
"1","(-3100,3125)","0","mstr_standard","I227";
;
CDS_LIB"mstr_standard"
BODY_TYPE"PLUMBING"
HDL_TAP"TRUE";
"B \NAC \NWC"9;
"S \NAC"
BN"5"146;
%"TAP"
"1","(-3100,3025)","0","mstr_standard","I228";
;
CDS_LIB"mstr_standard"
BODY_TYPE"PLUMBING"
HDL_TAP"TRUE";
"B \NAC \NWC"9;
"S \NAC"
BN"4"142;
%"TAP"
"1","(-3100,2925)","0","mstr_standard","I229";
;
CDS_LIB"mstr_standard"
BODY_TYPE"PLUMBING"
HDL_TAP"TRUE";
"B \NAC \NWC"9;
"S \NAC"
BN"3"138;
%"TAP"
"1","(-7325,3200)","2","mstr_standard","I23";
;
CDS_LIB"mstr_standard"
BODY_TYPE"PLUMBING"
HDL_TAP"TRUE";
"B \NAC \NWC"14;
"S \NAC"
BN"0"63;
%"TAP"
"1","(-2900,2775)","0","mstr_standard","I230";
;
CDS_LIB"mstr_standard"
BODY_TYPE"PLUMBING"
HDL_TAP"TRUE";
"B \NAC \NWC"10;
"S \NAC"
BN"2"133;
%"TAP"
"1","(-2900,2675)","0","mstr_standard","I231";
;
CDS_LIB"mstr_standard"
BODY_TYPE"PLUMBING"
HDL_TAP"TRUE";
"B \NAC \NWC"10;
"S \NAC"
BN"1"129;
%"TAP"
"1","(-2900,2575)","0","mstr_standard","I232";
;
CDS_LIB"mstr_standard"
BODY_TYPE"PLUMBING"
HDL_TAP"TRUE";
"B \NAC \NWC"10;
"S \NAC"
BN"0"125;
%"TAP"
"1","(-3100,2625)","0","mstr_standard","I233";
;
CDS_LIB"mstr_standard"
BODY_TYPE"PLUMBING"
HDL_TAP"TRUE";
"B \NAC \NWC"9;
"S \NAC"
BN"0"126;
%"TAP"
"1","(-3100,2725)","0","mstr_standard","I234";
;
CDS_LIB"mstr_standard"
BODY_TYPE"PLUMBING"
HDL_TAP"TRUE";
"B \NAC \NWC"9;
"S \NAC"
BN"1"130;
%"TAP"
"1","(-3100,2825)","0","mstr_standard","I235";
;
CDS_LIB"mstr_standard"
BODY_TYPE"PLUMBING"
HDL_TAP"TRUE";
"B \NAC \NWC"9;
"S \NAC"
BN"2"134;
%"SCONN288_DDR506112002KQ"
"2","(-4100,3575)","0","pure_quanta","I236";
;
LOCATION"J16"
$SEC"2"
CDS_SEC"2"
PART_TYPE"SMLF"
VALUE"SCONN288_DDR506112002KQ"
MATERIAL"IO"
CDS_LMAN_SYM_OUTLINE"-600,1150,600,-1150"
NEEDS_NO_SIZE"TRUE"
CDS_LIB"pure_quanta"
PART_NUMBER"DFHST8FS479";
"DQS7_A_C||TDQS7_A_C \B"
$PN"178"118;
"DQS6_A_T||TDQS6_A_T"
$PN"168"119;
"DQS8_B_T||TDQS8_B_T"
$PN"283"120;
"DQS8_B_C||TDQS8_B_C \B"
$PN"282"121;
"DQS7_B_T||TDQS7_B_T"
$PN"272"122;
"DQS0_A_C \B"
$PN"12"123;
"DQS0_A_T"
$PN"11"124;
"DQS0_B_C \B"
$PN"105"125;
"DQS0_B_T"
$PN"104"126;
"DQS1_A_C \B"
$PN"23"127;
"DQS1_A_T"
$PN"22"128;
"DQS1_B_C \B"
$PN"116"129;
"DQS1_B_T"
$PN"115"130;
"DQS2_A_C \B"
$PN"34"131;
"DQS2_A_T"
$PN"33"132;
"DQS2_B_C \B"
$PN"127"133;
"DQS2_B_T"
$PN"126"134;
"DQS3_A_C \B"
$PN"45"135;
"DQS3_A_T"
$PN"44"136;
"DQS3_B_C \B"
$PN"138"137;
"DQS3_B_T"
$PN"137"138;
"DQS4_A_C \B"
$PN"56"139;
"DQS4_A_T"
$PN"55"140;
"DQS4_B_C \B"
$PN"238"141;
"DQS4_B_T"
$PN"239"142;
"DQS5_A_C||TDQS5_A_C||DQS5_A_T||TDQS5_A_T \B"
$PN"156"143;
"DQS5_A_T||TDQS5_A_T"
$PN"157"144;
"DQS5_B_C||TDQS5_B_C \B"
$PN"249"145;
"DQS5_B_T||TDQS5_B_T"
$PN"250"146;
"DQS6_A_C||TDQS6_A_C||DQS6_A_T||TDQS6_A_T \B"
$PN"167"147;
"DQS6_B_C||TDQS6_B_C \B"
$PN"260"148;
"DQS6_B_T||TDQS6_B_T"
$PN"261"149;
"DQS7_A_T||TDQS7_A_T"
$PN"179"150;
"DQS7_B_C||TDQS7_B_C \B"
$PN"271"151;
"DQS8_A_C||TDQS8_A_C \B"
$PN"189"152;
"DQS8_A_T||TDQS8_A_T"
$PN"190"153;
"DQS9_A_C||TDQS9_A_C \B"
$PN"200"154;
"DQS9_A_T||TDQS9_A_T"
$PN"201"155;
"DQS9_B_C||TDQS9_B_C \B"
$PN"94"156;
"DQS9_B_T||TDQS9_B_T||DBI4_B_N"
$PN"93"157;
%"GND"
"1","(-2675,5525)","0","pure_quanta_power","I237";
;
CDS_LIB"pure_quanta_power"
BOM_COST"MEM"
SIZE"1B"
ROOM"MEM_EFGH_DECOUPLING_CAPS"
HDL_POWER"GND";
"A<SIZE-1..0>\NAC"27;
%"Q_CAP"
"1","(-2675,5875)","2","pure_quanta","I238";
;
LOCATION"C157"
$SEC"1"
CDS_SEC"1"
VALUE"10UF"
PACK_TYPE"C0805"
VOLTAGE"25V"
TOLERANCE"10%"
MATERIAL"X6S"
CDS_LIB"pure_quanta"
BOM_COST"MEM"
ROOM""
PART_NUMBER"CH6104KEA00";
"B"
$PN"2"27;
"A"
$PN"1"28;
%"Q_CAP"
"1","(-2100,5875)","2","pure_quanta","I239";
;
LOCATION"C158"
$SEC"1"
CDS_SEC"1"
PACK_TYPE"C0805"
VOLTAGE"25V"
VALUE"10UF"
TOLERANCE"10%"
MATERIAL"X6S"
CDS_LIB"pure_quanta"
BOM_COST"MEM"
ROOM""
PART_NUMBER"CH6104KEA00";
"B"
$PN"2"27;
"A"
$PN"1"28;
%"TAP"
"1","(-7325,3250)","2","mstr_standard","I24";
;
CDS_LIB"mstr_standard"
BODY_TYPE"PLUMBING"
HDL_TAP"TRUE";
"B \NAC \NWC"14;
"S \NAC"
BN"1"62;
%"UNIVERSAL_POWER"
"1","(-2675,6200)","0","pure_quanta_power","I240";
;
HDL_POWER"P12V_MEM_CPU0"
CDS_LIB"pure_quanta_power"
BOM_COST"VR_SYSTEM";
"A"28;
%"Q_RES"
"1","(-7375,2650)","0","pure_quanta","I242";
;
LOCATION"R1574"
$SEC"1"
CDS_SEC"1"
VALUE"49.9"
CDS_LIB"pure_quanta"
MATERIAL"CHIP"
PACK_TYPE"0402LF"
WATTAGE"1/16W"
TOLERANCE"1%"
PART_NUMBER"CS04992FB07";
"B"
$PN"2"33;
"A"
$PN"1"22;
%"Q_RES"
"2","(-8750,1300)","0","pure_quanta","I243";
;
LOCATION"R8038"
$SEC"1"
CDS_SEC"1"
VALUE"10K"
WATTAGE"1/16W"
TOLERANCE"1%"
PACK_TYPE"0402LF"
MATERIAL"CHIP"
CDS_LIB"pure_quanta"
PART_NUMBER"CS31002FB08";
"A"
$PN"1"5;
"B"
$PN"2"35;
%"VCC_CORE"
"1","(-8750,1600)","0","pure_quanta_power","I244";
;
HDL_POWER"P3V3_AUX"
ROOM"PVCCINFAON_CPU0_CTRL"
VOLTAGE"3.3"
CDS_LIB"pure_quanta_power";
"A"5;
%"VCC_CORE"
"1","(-4375,1450)","0","pure_quanta_power","I247";
;
HDL_POWER"P3V3_AUX"
CDS_LIB"pure_quanta_power"
ROOM"PVCCINFAON_CPU0_CTRL"
VOLTAGE"3.3";
"A"29;
%"Q_RES"
"1","(-3350,775)","0","pure_quanta","I248";
;
LOCATION"R8083"
$SEC"1"
CDS_SEC"1"
VALUE"0"
MATERIAL"CHIP"
TOLERANCE"5%"
PACK_TYPE"0402LF"
WATTAGE"1/16W"
CDS_LIB"pure_quanta"
PART_NUMBER"CS00002JB13";
"B"
$PN"2"36;
"A"
$PN"1"180;
%"Q_RES"
"1","(-3775,1250)","0","pure_quanta","I249";
;
LOCATION"R8085"
$SEC"1"
CDS_SEC"1"
VALUE"10K"
TOLERANCE"1%"
MATERIAL"EMPTY"
PACK_TYPE"0402LF"
WATTAGE"1/16W"
CDS_LIB"pure_quanta"
PART_NUMBER"CS31002FB08";
"B"
$PN"2"36;
"A"
$PN"1"29;
%"TAP"
"1","(-7325,3300)","2","mstr_standard","I25";
;
CDS_LIB"mstr_standard"
BODY_TYPE"PLUMBING"
HDL_TAP"TRUE";
"B \NAC \NWC"14;
"S \NAC"
BN"2"61;
%"Q_RES"
"1","(-1925,775)","0","pure_quanta","I250";
;
LOCATION"R8084"
$SEC"1"
CDS_SEC"1"
WATTAGE"1/16W"
PACK_TYPE"0402LF"
MATERIAL"CHIP"
TOLERANCE"5%"
VALUE"0"
CDS_LIB"pure_quanta"
PART_NUMBER"CS00002JB13";
"B"
$PN"2"37;
"A"
$PN"1"36;
%"SCHOTTKY_12"
"1","(-1825,1225)","0","pure_quanta","I251";
;
LOCATION"D8004"
$SEC"1"
CDS_SEC"1"
MATERIAL"EMPTY"
VALUE"B0530WS7F"
PART_TYPE"SMLF"
CDS_LIB"pure_quanta"
CDS_LMAN_SYM_OUTLINE"-75,50,75,-50"
NEEDS_NO_SIZE"TRUE"
PART_NUMBER"BC000530Z41";
"C"
$PN"2"30;
"A"
$PN"1"36;
%"VCC_CORE"
"1","(-1150,1350)","0","pure_quanta_power","I252";
;
HDL_POWER"P3V3_AUX"
CDS_LIB"pure_quanta_power"
VOLTAGE"3.3"
ROOM"PVCCINFAON_CPU0_CTRL";
"A"30;
%"Q_RES"
"1","(-7750,2850)","0","pure_quanta","I254";
;
LOCATION"R1680"
$SEC"1"
CDS_SEC"1"
MATERIAL"CHIP"
PACK_TYPE"0402LF"
VALUE"10"
TOLERANCE"1%"
WATTAGE"1/16W"
CDS_LIB"pure_quanta"
PART_NUMBER"CS01002FB07";
"B"
$PN"2"23;
"A"
$PN"1"16;
%"TAP"
"1","(-7325,3350)","2","mstr_standard","I26";
;
CDS_LIB"mstr_standard"
BODY_TYPE"PLUMBING"
HDL_TAP"TRUE";
"B \NAC \NWC"14;
"S \NAC"
BN"3"60;
%"TAP"
"1","(-7325,3400)","2","mstr_standard","I27";
;
CDS_LIB"mstr_standard"
BODY_TYPE"PLUMBING"
HDL_TAP"TRUE";
"B \NAC \NWC"14;
"S \NAC"
BN"4"59;
%"TAP"
"1","(-7325,3450)","2","mstr_standard","I28";
;
CDS_LIB"mstr_standard"
BODY_TYPE"PLUMBING"
HDL_TAP"TRUE";
"B \NAC \NWC"14;
"S \NAC"
BN"5"58;
%"TAP"
"1","(-7325,3500)","2","mstr_standard","I29";
;
CDS_LIB"mstr_standard"
BODY_TYPE"PLUMBING"
HDL_TAP"TRUE";
"B \NAC \NWC"14;
"S \NAC"
BN"6"57;
%"TAP"
"1","(-7325,3550)","2","mstr_standard","I30";
;
CDS_LIB"mstr_standard"
BODY_TYPE"PLUMBING"
HDL_TAP"TRUE";
"B \NAC \NWC"14;
"S \NAC"
BN"7"43;
%"TAP"
"1","(-7325,3650)","2","mstr_standard","I31";
;
CDS_LIB"mstr_standard"
BODY_TYPE"PLUMBING"
HDL_TAP"TRUE";
"B \NAC \NWC"15;
"S \NAC"
BN"0"56;
%"TAP"
"1","(-7325,3700)","2","mstr_standard","I32";
;
CDS_LIB"mstr_standard"
BODY_TYPE"PLUMBING"
HDL_TAP"TRUE";
"B \NAC \NWC"15;
"S \NAC"
BN"1"42;
%"TAP"
"1","(-7325,3750)","2","mstr_standard","I33";
;
CDS_LIB"mstr_standard"
BODY_TYPE"PLUMBING"
HDL_TAP"TRUE";
"B \NAC \NWC"15;
"S \NAC"
BN"2"55;
%"TAP"
"1","(-7325,3800)","2","mstr_standard","I34";
;
CDS_LIB"mstr_standard"
BODY_TYPE"PLUMBING"
HDL_TAP"TRUE";
"B \NAC \NWC"15;
"S \NAC"
BN"3"54;
%"TAP"
"1","(-7325,3850)","2","mstr_standard","I35";
;
CDS_LIB"mstr_standard"
BODY_TYPE"PLUMBING"
HDL_TAP"TRUE";
"B \NAC \NWC"15;
"S \NAC"
BN"4"41;
%"TAP"
"1","(-7325,3900)","2","mstr_standard","I36";
;
CDS_LIB"mstr_standard"
BODY_TYPE"PLUMBING"
HDL_TAP"TRUE";
"B \NAC \NWC"15;
"S \NAC"
BN"5"53;
%"TAP"
"1","(-7325,3950)","2","mstr_standard","I37";
;
CDS_LIB"mstr_standard"
BODY_TYPE"PLUMBING"
HDL_TAP"TRUE";
"B \NAC \NWC"15;
"S \NAC"
BN"6"21;
%"TAP"
"1","(-7325,4000)","2","mstr_standard","I38";
;
CDS_LIB"mstr_standard"
BODY_TYPE"PLUMBING"
HDL_TAP"TRUE";
"B \NAC \NWC"15;
"S \NAC"
BN"7"40;
%"TAP"
"1","(-5625,2250)","0","mstr_standard","I46";
;
CDS_LIB"mstr_standard"
BODY_TYPE"PLUMBING"
HDL_TAP"TRUE";
"B \NAC \NWC"13;
"S \NAC"
BN"1"108;
%"TAP"
"1","(-5625,2200)","0","mstr_standard","I47";
;
CDS_LIB"mstr_standard"
BODY_TYPE"PLUMBING"
HDL_TAP"TRUE";
"B \NAC \NWC"13;
"S \NAC"
BN"0"109;
%"TAP"
"1","(-5625,2400)","0","mstr_standard","I48";
;
CDS_LIB"mstr_standard"
BODY_TYPE"PLUMBING"
HDL_TAP"TRUE";
"B \NAC \NWC"13;
"S \NAC"
BN"4"105;
%"TAP"
"1","(-5625,2350)","0","mstr_standard","I49";
;
CDS_LIB"mstr_standard"
BODY_TYPE"PLUMBING"
HDL_TAP"TRUE";
"B \NAC \NWC"13;
"S \NAC"
BN"3"106;
%"TAP"
"1","(-5625,2300)","0","mstr_standard","I50";
;
CDS_LIB"mstr_standard"
BODY_TYPE"PLUMBING"
HDL_TAP"TRUE";
"B \NAC \NWC"13;
"S \NAC"
BN"2"107;
%"TAP"
"1","(-5625,2450)","0","mstr_standard","I51";
;
CDS_LIB"mstr_standard"
BODY_TYPE"PLUMBING"
HDL_TAP"TRUE";
"B \NAC \NWC"13;
"S \NAC"
BN"5"104;
%"TAP"
"1","(-5625,2500)","0","mstr_standard","I52";
;
CDS_LIB"mstr_standard"
BODY_TYPE"PLUMBING"
HDL_TAP"TRUE";
"B \NAC \NWC"13;
"S \NAC"
BN"6"103;
%"TAP"
"1","(-5625,2650)","0","mstr_standard","I53";
;
CDS_LIB"mstr_standard"
BODY_TYPE"PLUMBING"
HDL_TAP"TRUE";
"B \NAC \NWC"13;
"S \NAC"
BN"9"100;
%"TAP"
"1","(-5625,2600)","0","mstr_standard","I54";
;
CDS_LIB"mstr_standard"
BODY_TYPE"PLUMBING"
HDL_TAP"TRUE";
"B \NAC \NWC"13;
"S \NAC"
BN"8"101;
%"TAP"
"1","(-5625,2550)","0","mstr_standard","I55";
;
CDS_LIB"mstr_standard"
BODY_TYPE"PLUMBING"
HDL_TAP"TRUE";
"B \NAC \NWC"13;
"S \NAC"
BN"7"102;
%"TAP"
"1","(-5625,2700)","0","mstr_standard","I56";
;
CDS_LIB"mstr_standard"
BODY_TYPE"PLUMBING"
HDL_TAP"TRUE";
"B \NAC \NWC"13;
"S \NAC"
BN"10"99;
%"TAP"
"1","(-5625,2750)","0","mstr_standard","I57";
;
CDS_LIB"mstr_standard"
BODY_TYPE"PLUMBING"
HDL_TAP"TRUE";
"B \NAC \NWC"13;
"S \NAC"
BN"11"98;
%"TAP"
"1","(-5625,2900)","0","mstr_standard","I58";
;
CDS_LIB"mstr_standard"
BODY_TYPE"PLUMBING"
HDL_TAP"TRUE";
"B \NAC \NWC"13;
"S \NAC"
BN"14"95;
%"TAP"
"1","(-5625,2850)","0","mstr_standard","I59";
;
CDS_LIB"mstr_standard"
BODY_TYPE"PLUMBING"
HDL_TAP"TRUE";
"B \NAC \NWC"13;
"S \NAC"
BN"13"96;
%"TAP"
"1","(-5625,2800)","0","mstr_standard","I60";
;
CDS_LIB"mstr_standard"
BODY_TYPE"PLUMBING"
HDL_TAP"TRUE";
"B \NAC \NWC"13;
"S \NAC"
BN"12"97;
%"TAP"
"1","(-5625,3000)","0","mstr_standard","I61";
;
CDS_LIB"mstr_standard"
BODY_TYPE"PLUMBING"
HDL_TAP"TRUE";
"B \NAC \NWC"13;
"S \NAC"
BN"16"93;
%"TAP"
"1","(-5625,2950)","0","mstr_standard","I62";
;
CDS_LIB"mstr_standard"
BODY_TYPE"PLUMBING"
HDL_TAP"TRUE";
"B \NAC \NWC"13;
"S \NAC"
BN"15"94;
%"TAP"
"1","(-5625,3050)","0","mstr_standard","I63";
;
CDS_LIB"mstr_standard"
BODY_TYPE"PLUMBING"
HDL_TAP"TRUE";
"B \NAC \NWC"13;
"S \NAC"
BN"17"92;
%"TAP"
"1","(-5625,3150)","0","mstr_standard","I64";
;
CDS_LIB"mstr_standard"
BODY_TYPE"PLUMBING"
HDL_TAP"TRUE";
"B \NAC \NWC"13;
"S \NAC"
BN"19"90;
%"TAP"
"1","(-5625,3100)","0","mstr_standard","I65";
;
CDS_LIB"mstr_standard"
BODY_TYPE"PLUMBING"
HDL_TAP"TRUE";
"B \NAC \NWC"13;
"S \NAC"
BN"18"91;
%"TAP"
"1","(-5625,3200)","0","mstr_standard","I66";
;
CDS_LIB"mstr_standard"
BODY_TYPE"PLUMBING"
HDL_TAP"TRUE";
"B \NAC \NWC"13;
"S \NAC"
BN"20"89;
%"TAP"
"1","(-5625,3250)","0","mstr_standard","I67";
;
CDS_LIB"mstr_standard"
BODY_TYPE"PLUMBING"
HDL_TAP"TRUE";
"B \NAC \NWC"13;
"S \NAC"
BN"21"19;
%"TAP"
"1","(-5625,3300)","0","mstr_standard","I68";
;
CDS_LIB"mstr_standard"
BODY_TYPE"PLUMBING"
HDL_TAP"TRUE";
"B \NAC \NWC"13;
"S \NAC"
BN"22"88;
%"TAP"
"1","(-5625,3400)","0","mstr_standard","I69";
;
CDS_LIB"mstr_standard"
BODY_TYPE"PLUMBING"
HDL_TAP"TRUE";
"B \NAC \NWC"13;
"S \NAC"
BN"24"86;
%"TAP"
"1","(-5625,3350)","0","mstr_standard","I70";
;
CDS_LIB"mstr_standard"
BODY_TYPE"PLUMBING"
HDL_TAP"TRUE";
"B \NAC \NWC"13;
"S \NAC"
BN"23"87;
%"TAP"
"1","(-5625,3450)","0","mstr_standard","I71";
;
CDS_LIB"mstr_standard"
BODY_TYPE"PLUMBING"
HDL_TAP"TRUE";
"B \NAC \NWC"13;
"S \NAC"
BN"25"85;
%"TAP"
"1","(-5625,3500)","0","mstr_standard","I72";
;
CDS_LIB"mstr_standard"
BODY_TYPE"PLUMBING"
HDL_TAP"TRUE";
"B \NAC \NWC"13;
"S \NAC"
BN"26"20;
%"TAP"
"1","(-5625,3550)","0","mstr_standard","I73";
;
CDS_LIB"mstr_standard"
BODY_TYPE"PLUMBING"
HDL_TAP"TRUE";
"B \NAC \NWC"13;
"S \NAC"
BN"27"84;
%"TAP"
"1","(-5625,3650)","0","mstr_standard","I74";
;
CDS_LIB"mstr_standard"
BODY_TYPE"PLUMBING"
HDL_TAP"TRUE";
"B \NAC \NWC"13;
"S \NAC"
BN"29"82;
%"TAP"
"1","(-5625,3600)","0","mstr_standard","I75";
;
CDS_LIB"mstr_standard"
BODY_TYPE"PLUMBING"
HDL_TAP"TRUE";
"B \NAC \NWC"13;
"S \NAC"
BN"28"83;
%"TAP"
"1","(-5625,3700)","0","mstr_standard","I76";
;
CDS_LIB"mstr_standard"
BODY_TYPE"PLUMBING"
HDL_TAP"TRUE";
"B \NAC \NWC"13;
"S \NAC"
BN"30"81;
%"TAP"
"1","(-5625,3750)","0","mstr_standard","I77";
;
CDS_LIB"mstr_standard"
BODY_TYPE"PLUMBING"
HDL_TAP"TRUE";
"B \NAC \NWC"13;
"S \NAC"
BN"31"80;
%"TAP"
"1","(-5625,3900)","0","mstr_standard","I78";
;
CDS_LIB"mstr_standard"
BODY_TYPE"PLUMBING"
HDL_TAP"TRUE";
"B \NAC \NWC"6;
"S \NAC"
BN"1"78;
%"TAP"
"1","(-5625,3850)","0","mstr_standard","I79";
;
CDS_LIB"mstr_standard"
BODY_TYPE"PLUMBING"
HDL_TAP"TRUE";
"B \NAC \NWC"6;
"S \NAC"
BN"0"79;
%"VCC_CORE"
"1","(-8400,3450)","0","mstr_symbols","I8";
;
HDL_POWER"P3V3_AUX"
CDS_LIB"mstr_symbols"
VOLTAGE"3.3"
ROOM"PVCCINFAON_CPU0_CTRL";
"A"18;
%"TAP"
"1","(-5625,4000)","0","mstr_standard","I80";
;
CDS_LIB"mstr_standard"
BODY_TYPE"PLUMBING"
HDL_TAP"TRUE";
"B \NAC \NWC"6;
"S \NAC"
BN"3"76;
%"TAP"
"1","(-5625,4050)","0","mstr_standard","I81";
;
CDS_LIB"mstr_standard"
BODY_TYPE"PLUMBING"
HDL_TAP"TRUE";
"B \NAC \NWC"6;
"S \NAC"
BN"4"75;
%"TAP"
"1","(-5625,3950)","0","mstr_standard","I82";
;
CDS_LIB"mstr_standard"
BODY_TYPE"PLUMBING"
HDL_TAP"TRUE";
"B \NAC \NWC"6;
"S \NAC"
BN"2"77;
%"TAP"
"1","(-7325,4700)","2","mstr_standard","I85";
;
CDS_LIB"mstr_standard"
BODY_TYPE"PLUMBING"
HDL_TAP"TRUE";
"B \NAC \NWC"8;
"S \NAC"
BN"0"44;
%"TAP"
"1","(-7325,4750)","2","mstr_standard","I86";
;
CDS_LIB"mstr_standard"
BODY_TYPE"PLUMBING"
HDL_TAP"TRUE";
"B \NAC \NWC"8;
"S \NAC"
BN"1"46;
%"TAP"
"1","(-7325,4800)","2","mstr_standard","I87";
;
CDS_LIB"mstr_standard"
BODY_TYPE"PLUMBING"
HDL_TAP"TRUE";
"B \NAC \NWC"8;
"S \NAC"
BN"2"48;
%"TAP"
"1","(-7325,4850)","2","mstr_standard","I88";
;
CDS_LIB"mstr_standard"
BODY_TYPE"PLUMBING"
HDL_TAP"TRUE";
"B \NAC \NWC"8;
"S \NAC"
BN"3"172;
%"TAP"
"1","(-7325,4900)","2","mstr_standard","I89";
;
CDS_LIB"mstr_standard"
BODY_TYPE"PLUMBING"
HDL_TAP"TRUE";
"B \NAC \NWC"8;
"S \NAC"
BN"4"173;
%"TAP"
"1","(-7325,4950)","2","mstr_standard","I90";
;
CDS_LIB"mstr_standard"
BODY_TYPE"PLUMBING"
HDL_TAP"TRUE";
"B \NAC \NWC"8;
"S \NAC"
BN"5"174;
%"TAP"
"1","(-7325,5000)","2","mstr_standard","I91";
;
CDS_LIB"mstr_standard"
BODY_TYPE"PLUMBING"
HDL_TAP"TRUE";
"B \NAC \NWC"8;
"S \NAC"
BN"6"175;
%"TAP"
"1","(-7325,5150)","2","mstr_standard","I92";
;
CDS_LIB"mstr_standard"
BODY_TYPE"PLUMBING"
HDL_TAP"TRUE";
"B \NAC \NWC"7;
"S \NAC"
BN"1"45;
%"TAP"
"1","(-7325,5100)","2","mstr_standard","I93";
;
CDS_LIB"mstr_standard"
BODY_TYPE"PLUMBING"
HDL_TAP"TRUE";
"B \NAC \NWC"7;
"S \NAC"
BN"0"176;
%"TAP"
"1","(-7325,5200)","2","mstr_standard","I94";
;
CDS_LIB"mstr_standard"
BODY_TYPE"PLUMBING"
HDL_TAP"TRUE";
"B \NAC \NWC"7;
"S \NAC"
BN"2"47;
%"TAP"
"1","(-7325,5250)","2","mstr_standard","I95";
;
CDS_LIB"mstr_standard"
BODY_TYPE"PLUMBING"
HDL_TAP"TRUE";
"B \NAC \NWC"7;
"S \NAC"
BN"3"49;
%"TAP"
"1","(-7325,5300)","2","mstr_standard","I96";
;
CDS_LIB"mstr_standard"
BODY_TYPE"PLUMBING"
HDL_TAP"TRUE";
"B \NAC \NWC"7;
"S \NAC"
BN"4"50;
%"TAP"
"1","(-7325,5350)","2","mstr_standard","I97";
;
CDS_LIB"mstr_standard"
BODY_TYPE"PLUMBING"
HDL_TAP"TRUE";
"B \NAC \NWC"7;
"S \NAC"
BN"5"51;
%"TAP"
"1","(-7325,5400)","2","mstr_standard","I98";
;
CDS_LIB"mstr_standard"
BODY_TYPE"PLUMBING"
HDL_TAP"TRUE";
"B \NAC \NWC"7;
"S \NAC"
BN"6"52;
%"TAP"
"1","(-5625,4150)","0","mstr_standard","I99";
;
CDS_LIB"mstr_standard"
BODY_TYPE"PLUMBING"
HDL_TAP"TRUE";
"B \NAC \NWC"6;
"S \NAC"
BN"6"73;
END.
